(kicad_pcb
	(version 20260206)
	(generator "pcbnew")
	(generator_version "10.0")
	(general
		(thickness 1.6)
		(legacy_teardrops no)
	)
	(paper "A4")
	(title_block
		(title "v2-pdb — ms_pdb_v2.brd")
		(comment 1 "Open CloudServer (Microsoft) / footprint 336 of 348 (J8), pads 1-46 of 46")
	)
	(layers
		(0 "F.Cu" signal "TOP")
		(4 "In1.Cu" signal "GND")
		(6 "In2.Cu" signal "IN1")
		(8 "In3.Cu" signal "VCC")
		(10 "In4.Cu" signal "VCC1")
		(12 "In5.Cu" signal "IN2")
		(14 "In6.Cu" signal "GND1")
		(2 "B.Cu" signal "BOTTOM")
		(9 "F.Adhes" user "F.Adhesive")
		(11 "B.Adhes" user "B.Adhesive")
		(13 "F.Paste" user "Package Geometry/Pastemask Top")
		(15 "B.Paste" user "Package Geometry/Pastemask Bottom")
		(5 "F.SilkS" user "Ref Des/Silkscreen Top")
		(7 "B.SilkS" user "Ref Des/Silkscreen Bottom")
		(1 "F.Mask" user "Board Geometry/Soldermask Top")
		(3 "B.Mask" user "Board Geometry/Soldermask Bottom")
		(17 "Dwgs.User" user "User.Drawings")
		(19 "Cmts.User" user "User.Comments")
		(21 "Eco1.User" user "User.Eco1")
		(23 "Eco2.User" user "User.Eco2")
		(25 "Edge.Cuts" user "Board Geometry/Outline")
		(27 "Margin" user)
		(31 "F.CrtYd" user "Package Geometry/Place Bound Top")
		(29 "B.CrtYd" user "Package Geometry/Place Bound Bottom")
		(35 "F.Fab" user "Ref Des/Assembly Top")
		(33 "B.Fab" user "Ref Des/Assembly Bottom")
	)
	(footprint ""
		(layer "B.Cu")
		(at 44.03979 -52.71008 90)
		(property "Reference" "J8"
			(at 6.17982 -4.9149 0)
			(unlocked yes)
			(layer "B.SilkS")
			(effects
				(font
					(size 0.7874 0.5842)
					(thickness 0.1524)
				)
				(justify left mirror)
			)
		)
		(property "Value" ""
			(at 0 0 90)
			(layer "B.Fab")
			(effects
				(font
					(size 1.27 1.27)
				)
				(justify mirror)
			)
		)
		(duplicate_pad_numbers_are_jumpers no)
		(pad "" np_thru_hole circle
			(at -1.35001 -2.54)
			(size 2.5146 2.5146)
			(drill 2.5146)
			(layers "*.Cu" "*.Mask")
			(clearance 0.381)
			(thermal_gap 0.381)
		)
		(pad "" np_thru_hole circle
			(at 0 50.8)
			(size 2.5146 2.5146)
			(drill 2.5146)
			(layers "*.Cu" "*.Mask")
			(clearance 0.381)
			(thermal_gap 0.381)
		)
		(pad "P1" thru_hole rect
			(at 0 0)
			(size 1.1684 1.1684)
			(drill 0.762)
			(layers "*.Cu" "*.Mask")
			(remove_unused_layers no)
			(net "GND")
			(clearance 0.0508)
			(padstack
				(mode front_inner_back)
				(layer "Inner"
					(shape circle)
					(size 1.1684 1.1684)
					(clearance 0.0508)
				)
				(layer "B.Cu"
					(shape rect)
					(size 1.1684 1.1684)
					(thermal_gap 0.0508)
					(clearance 0.0508)
				)
			)
		)
		(pad "P2" thru_hole circle
			(at 0 2.54)
			(size 1.1684 1.1684)
			(drill 0.762)
			(layers "*.Cu" "*.Mask")
			(remove_unused_layers no)
			(net "GND")
			(clearance 0.0508)
			(thermal_gap 0.0508)
		)
		(pad "P3" thru_hole circle
			(at 0 5.08)
			(size 1.1684 1.1684)
			(drill 0.762)
			(layers "*.Cu" "*.Mask")
			(remove_unused_layers no)
			(net "GND")
			(clearance 0.0508)
			(thermal_gap 0.0508)
		)
		(pad "P4" thru_hole circle
			(at 0 7.62)
			(size 1.1684 1.1684)
			(drill 0.762)
			(layers "*.Cu" "*.Mask")
			(remove_unused_layers no)
			(net "GND")
			(clearance 0.0508)
			(thermal_gap 0.0508)
		)
		(pad "P5" thru_hole circle
			(at 0 10.16)
			(size 1.1684 1.1684)
			(drill 0.762)
			(layers "*.Cu" "*.Mask")
			(remove_unused_layers no)
			(net "GND")
			(clearance 0.0508)
			(thermal_gap 0.0508)
		)
		(pad "P6" thru_hole circle
			(at 0 12.7)
			(size 1.1684 1.1684)
			(drill 0.762)
			(layers "*.Cu" "*.Mask")
			(remove_unused_layers no)
			(net "GND")
			(clearance 0.0508)
			(thermal_gap 0.0508)
		)
		(pad "P7" thru_hole circle
			(at 0 15.24)
			(size 1.1684 1.1684)
			(drill 0.762)
			(layers "*.Cu" "*.Mask")
			(remove_unused_layers no)
			(net "GND")
			(clearance 0.0508)
			(thermal_gap 0.0508)
		)
		(pad "P8" thru_hole circle
			(at 0 17.78)
			(size 1.1684 1.1684)
			(drill 0.762)
			(layers "*.Cu" "*.Mask")
			(remove_unused_layers no)
			(net "GND")
			(clearance 0.0508)
			(thermal_gap 0.0508)
		)
		(pad "P9" thru_hole circle
			(at 0 20.32)
			(size 1.1684 1.1684)
			(drill 0.762)
			(layers "*.Cu" "*.Mask")
			(remove_unused_layers no)
			(net "P12V")
			(clearance 0.0508)
			(thermal_gap 0.0508)
		)
		(pad "P10" thru_hole circle
			(at 0 22.86)
			(size 1.1684 1.1684)
			(drill 0.762)
			(layers "*.Cu" "*.Mask")
			(remove_unused_layers no)
			(net "P12V")
			(clearance 0.0508)
			(thermal_gap 0.0508)
		)
		(pad "P11" thru_hole circle
			(at 0 25.4)
			(size 1.1684 1.1684)
			(drill 0.762)
			(layers "*.Cu" "*.Mask")
			(remove_unused_layers no)
			(net "P12V")
			(clearance 0.0508)
			(thermal_gap 0.0508)
		)
		(pad "P12" thru_hole circle
			(at 0 27.94)
			(size 1.1684 1.1684)
			(drill 0.762)
			(layers "*.Cu" "*.Mask")
			(remove_unused_layers no)
			(net "P12V")
			(clearance 0.0508)
			(thermal_gap 0.0508)
		)
		(pad "P13" thru_hole circle
			(at 0 30.48)
			(size 1.1684 1.1684)
			(drill 0.762)
			(layers "*.Cu" "*.Mask")
			(remove_unused_layers no)
			(net "P12V")
			(clearance 0.0508)
			(thermal_gap 0.0508)
		)
		(pad "P14" thru_hole circle
			(at 0 33.02)
			(size 1.1684 1.1684)
			(drill 0.762)
			(layers "*.Cu" "*.Mask")
			(remove_unused_layers no)
			(net "P12V")
			(clearance 0.0508)
			(thermal_gap 0.0508)
		)
		(pad "P15" thru_hole circle
			(at 0 35.56)
			(size 1.1684 1.1684)
			(drill 0.762)
			(layers "*.Cu" "*.Mask")
			(remove_unused_layers no)
			(net "P12V")
			(clearance 0.0508)
			(thermal_gap 0.0508)
		)
		(pad "P16" thru_hole circle
			(at 0 38.1)
			(size 1.1684 1.1684)
			(drill 0.762)
			(layers "*.Cu" "*.Mask")
			(remove_unused_layers no)
			(net "P12V")
			(clearance 0.0508)
			(thermal_gap 0.0508)
		)
		(pad "P17" thru_hole circle
			(at -2.70002 38.1)
			(size 1.1684 1.1684)
			(drill 0.762)
			(layers "*.Cu" "*.Mask")
			(remove_unused_layers no)
			(net "P12V")
			(clearance 0.0508)
			(thermal_gap 0.0508)
		)
		(pad "P18" thru_hole circle
			(at -2.70002 35.56)
			(size 1.1684 1.1684)
			(drill 0.762)
			(layers "*.Cu" "*.Mask")
			(remove_unused_layers no)
			(net "P12V")
			(clearance 0.0508)
			(thermal_gap 0.0508)
		)
		(pad "P19" thru_hole circle
			(at -2.70002 33.02)
			(size 1.1684 1.1684)
			(drill 0.762)
			(layers "*.Cu" "*.Mask")
			(remove_unused_layers no)
			(net "P12V")
			(clearance 0.0508)
			(thermal_gap 0.0508)
		)
		(pad "P20" thru_hole circle
			(at -2.70002 30.48)
			(size 1.1684 1.1684)
			(drill 0.762)
			(layers "*.Cu" "*.Mask")
			(remove_unused_layers no)
			(net "P12V")
			(clearance 0.0508)
			(thermal_gap 0.0508)
		)
		(pad "P21" thru_hole circle
			(at -2.70002 27.94)
			(size 1.1684 1.1684)
			(drill 0.762)
			(layers "*.Cu" "*.Mask")
			(remove_unused_layers no)
			(net "P12V")
			(clearance 0.0508)
			(thermal_gap 0.0508)
		)
		(pad "P22" thru_hole circle
			(at -2.70002 25.4)
			(size 1.1684 1.1684)
			(drill 0.762)
			(layers "*.Cu" "*.Mask")
			(remove_unused_layers no)
			(net "P12V")
			(clearance 0.0508)
			(thermal_gap 0.0508)
		)
		(pad "P23" thru_hole circle
			(at -2.70002 22.86)
			(size 1.1684 1.1684)
			(drill 0.762)
			(layers "*.Cu" "*.Mask")
			(remove_unused_layers no)
			(net "P12V")
			(clearance 0.0508)
			(thermal_gap 0.0508)
		)
		(pad "P24" thru_hole circle
			(at -2.70002 20.32)
			(size 1.1684 1.1684)
			(drill 0.762)
			(layers "*.Cu" "*.Mask")
			(remove_unused_layers no)
			(net "P12V")
			(clearance 0.0508)
			(thermal_gap 0.0508)
		)
		(pad "P25" thru_hole circle
			(at -2.70002 17.78)
			(size 1.1684 1.1684)
			(drill 0.762)
			(layers "*.Cu" "*.Mask")
			(remove_unused_layers no)
			(net "GND")
			(clearance 0.0508)
			(thermal_gap 0.0508)
		)
		(pad "P26" thru_hole circle
			(at -2.70002 15.24)
			(size 1.1684 1.1684)
			(drill 0.762)
			(layers "*.Cu" "*.Mask")
			(remove_unused_layers no)
			(net "GND")
			(clearance 0.0508)
			(thermal_gap 0.0508)
		)
		(pad "P27" thru_hole circle
			(at -2.70002 12.7)
			(size 1.1684 1.1684)
			(drill 0.762)
			(layers "*.Cu" "*.Mask")
			(remove_unused_layers no)
			(net "GND")
			(clearance 0.0508)
			(thermal_gap 0.0508)
		)
		(pad "P28" thru_hole circle
			(at -2.70002 10.16)
			(size 1.1684 1.1684)
			(drill 0.762)
			(layers "*.Cu" "*.Mask")
			(remove_unused_layers no)
			(net "GND")
			(clearance 0.0508)
			(thermal_gap 0.0508)
		)
		(pad "P29" thru_hole circle
			(at -2.70002 7.62)
			(size 1.1684 1.1684)
			(drill 0.762)
			(layers "*.Cu" "*.Mask")
			(remove_unused_layers no)
			(net "GND")
			(clearance 0.0508)
			(thermal_gap 0.0508)
		)
		(pad "P30" thru_hole circle
			(at -2.70002 5.08)
			(size 1.1684 1.1684)
			(drill 0.762)
			(layers "*.Cu" "*.Mask")
			(remove_unused_layers no)
			(net "GND")
			(clearance 0.0508)
			(thermal_gap 0.0508)
		)
		(pad "P31" thru_hole circle
			(at -2.70002 2.54)
			(size 1.1684 1.1684)
			(drill 0.762)
			(layers "*.Cu" "*.Mask")
			(remove_unused_layers no)
			(net "GND")
			(clearance 0.0508)
			(thermal_gap 0.0508)
		)
		(pad "P32" thru_hole circle
			(at -2.70002 0)
			(size 1.1684 1.1684)
			(drill 0.762)
			(layers "*.Cu" "*.Mask")
			(remove_unused_layers no)
			(net "GND")
			(clearance 0.0508)
			(thermal_gap 0.0508)
		)
		(pad "S1" thru_hole circle
			(at 0.55499 41.60012)
			(size 1.1684 1.1684)
			(drill 0.762)
			(layers "*.Cu" "*.Mask")
			(remove_unused_layers no)
			(net "T2_BLAD1_TXD")
			(clearance 0.0508)
			(thermal_gap 0.0508)
		)
		(pad "S2" thru_hole circle
			(at -0.71501 42.87012)
			(size 1.1684 1.1684)
			(drill 0.762)
			(layers "*.Cu" "*.Mask")
			(remove_unused_layers no)
			(net "T2_BLAD1_RXD")
			(clearance 0.0508)
			(thermal_gap 0.0508)
		)
		(pad "S3" thru_hole circle
			(at 0.55499 44.14012)
			(size 1.1684 1.1684)
			(drill 0.762)
			(layers "*.Cu" "*.Mask")
			(remove_unused_layers no)
			(net "T2_BLAD1_EN")
			(clearance 0.0508)
			(thermal_gap 0.0508)
		)
		(pad "S4" thru_hole circle
			(at -0.71501 45.41012)
			(size 1.1684 1.1684)
			(drill 0.762)
			(layers "*.Cu" "*.Mask")
			(remove_unused_layers no)
			(net "B3_PSU_ALERT_N")
			(clearance 0.0508)
			(thermal_gap 0.0508)
		)
		(pad "S5" thru_hole circle
			(at 0.55499 46.68012)
			(size 1.1684 1.1684)
			(drill 0.762)
			(layers "*.Cu" "*.Mask")
			(remove_unused_layers no)
			(net "T2_BLAD2_TXD")
			(clearance 0.0508)
			(thermal_gap 0.0508)
		)
		(pad "S6" thru_hole circle
			(at -0.71501 47.95012)
			(size 1.1684 1.1684)
			(drill 0.762)
			(layers "*.Cu" "*.Mask")
			(remove_unused_layers no)
			(net "T2_BLAD2_RXD")
			(clearance 0.0508)
			(thermal_gap 0.0508)
		)
		(pad "S7" thru_hole circle
			(at -3.25501 47.95012)
			(size 1.1684 1.1684)
			(drill 0.762)
			(layers "*.Cu" "*.Mask")
			(remove_unused_layers no)
			(net "T2_BLAD4_RXD")
			(clearance 0.0508)
			(thermal_gap 0.0508)
		)
		(pad "S8" thru_hole circle
			(at -1.98501 46.68012)
			(size 1.1684 1.1684)
			(drill 0.762)
			(layers "*.Cu" "*.Mask")
			(remove_unused_layers no)
			(net "T2_BLAD4_TXD")
			(clearance 0.0508)
			(thermal_gap 0.0508)
		)
		(pad "S9" thru_hole circle
			(at -3.25501 45.41012)
			(size 1.1684 1.1684)
			(drill 0.762)
			(layers "*.Cu" "*.Mask")
			(remove_unused_layers no)
			(net "B4_PSU_ALERT_N")
			(clearance 0.0508)
			(thermal_gap 0.0508)
		)
		(pad "S10" thru_hole circle
			(at -1.98501 44.14012)
			(size 1.1684 1.1684)
			(drill 0.762)
			(layers "*.Cu" "*.Mask")
			(remove_unused_layers no)
			(net "T2_BLAD3_EN")
			(clearance 0.0508)
			(thermal_gap 0.0508)
		)
		(pad "S11" thru_hole circle
			(at -3.25501 42.87012)
			(size 1.1684 1.1684)
			(drill 0.762)
			(layers "*.Cu" "*.Mask")
			(remove_unused_layers no)
			(net "T2_BLAD3_RXD")
			(clearance 0.0508)
			(thermal_gap 0.0508)
		)
		(pad "S12" thru_hole circle
			(at -1.98501 41.60012)
			(size 1.1684 1.1684)
			(drill 0.762)
			(layers "*.Cu" "*.Mask")
			(remove_unused_layers no)
			(net "T2_BLAD3_TXD")
			(clearance 0.0508)
			(thermal_gap 0.0508)
		)
	)
)
